(kicad_pcb
	(version 20241229)
	(generator "pcbnew")
	(generator_version "9.0")
	(general
		(thickness 1.61)
		(legacy_teardrops no)
	)
	(paper "A3")
	(title_block
		(title "RDIMM DDR5 Tester")
		(date "2026-05-21")
		(rev "2.2.0")
		(company "Antmicro")
		(comment 9 "footprints 285-289 of 796")
	)
	(layers
		(0 "F.Cu" signal)
		(4 "In1.Cu" power)
		(6 "In2.Cu" mixed)
		(8 "In3.Cu" power)
		(10 "In4.Cu" mixed)
		(12 "In5.Cu" power)
		(14 "In6.Cu" mixed)
		(16 "In7.Cu" power)
		(18 "In8.Cu" power)
		(20 "In9.Cu" mixed)
		(22 "In10.Cu" power)
		(2 "B.Cu" signal)
		(9 "F.Adhes" user "F.Adhesive")
		(11 "B.Adhes" user "B.Adhesive")
		(13 "F.Paste" user)
		(15 "B.Paste" user)
		(5 "F.SilkS" user "F.Silkscreen")
		(7 "B.SilkS" user "B.Silkscreen")
		(1 "F.Mask" user)
		(3 "B.Mask" user)
		(17 "Dwgs.User" user "User.Drawings")
		(19 "Cmts.User" user "User.Comments")
		(21 "Eco1.User" user "User.Eco1")
		(23 "Eco2.User" user "User.Eco2")
		(25 "Edge.Cuts" user)
		(27 "Margin" user)
		(31 "F.CrtYd" user "F.Courtyard")
		(29 "B.CrtYd" user "B.Courtyard")
		(35 "F.Fab" user)
		(33 "B.Fab" user)
	)
	(footprint "antmicro-footprints:R_0402_1005Metric"
		(layer "F.Cu")
		(at 118.098 112.72 -90)
		(descr "Resistor SMD 0402")
		(tags "resistor SMD 0402")
		(property "Reference" "R12"
			(at -1.12 -1.427 90)
			(layer "F.SilkS")
			(effects
				(font
					(size 0.7 0.7)
					(thickness 0.15)
				)
				(justify right bottom)
			)
		)
		(property "Value" "R_330R_0402"
			(at -1.011843 1.772047 90)
			(layer "F.Fab")
			(effects
				(font
					(size 0.7 0.7)
					(thickness 0.15)
				)
				(justify right bottom)
			)
		)
		(property "Datasheet" "https://www.bourns.com/docs/product-datasheets/cr.pdf"
			(at 0 0 270)
			(layer "F.Fab")
			(hide yes)
			(effects
				(font
					(size 1.27 1.27)
					(thickness 0.15)
				)
			)
		)
		(property "Manufacturer" "Bourns"
			(at 0 0 270)
			(unlocked yes)
			(layer "F.Fab")
			(hide yes)
			(effects
				(font
					(size 1 1)
					(thickness 0.15)
				)
			)
		)
		(property "MPN" "CR0402-FX-3300GLF"
			(at 0 0 270)
			(unlocked yes)
			(layer "F.Fab")
			(hide yes)
			(effects
				(font
					(size 1 1)
					(thickness 0.15)
				)
			)
		)
		(property "Val" "330R"
			(at 0 0 270)
			(unlocked yes)
			(layer "F.Fab")
			(hide yes)
			(effects
				(font
					(size 1 1)
					(thickness 0.15)
				)
			)
		)
		(property "License" "Apache-2.0"
			(at 0 0 270)
			(unlocked yes)
			(layer "F.Fab")
			(hide yes)
			(effects
				(font
					(size 1 1)
					(thickness 0.15)
				)
			)
		)
		(property "Author" "Antmicro"
			(at 0 0 270)
			(unlocked yes)
			(layer "F.Fab")
			(hide yes)
			(effects
				(font
					(size 1 1)
					(thickness 0.15)
				)
			)
		)
		(property "Tolerance" "1%"
			(at 0 0 270)
			(unlocked yes)
			(layer "F.Fab")
			(hide yes)
			(effects
				(font
					(size 1 1)
					(thickness 0.15)
				)
			)
		)
		(sheetname "/FPGA Config/")
		(sheetfile "fpga-config.kicad_sch")
		(attr smd)
		(fp_rect
			(start -0.925 -0.47)
			(end 0.925 0.47)
			(stroke
				(width 0.05)
				(type default)
			)
			(fill no)
			(layer "F.CrtYd")
		)
		(fp_rect
			(start -0.5 -0.25)
			(end 0.5 0.25)
			(stroke
				(width 0.15)
				(type solid)
			)
			(fill no)
			(layer "F.Fab")
		)
		(fp_text user "License: Apache-2.0"
			(at -0.95 5.169 270)
			(layer "F.Fab")
			(effects
				(font
					(size 0.7 0.7)
					(thickness 0.15)
				)
				(justify left bottom)
			)
		)
		(fp_text user "Author: Antmicro"
			(at -0.95 4.169 270)
			(layer "F.Fab")
			(effects
				(font
					(size 0.7 0.7)
					(thickness 0.15)
				)
				(justify left bottom)
			)
		)
		(fp_text user "${REFERENCE}"
			(at -0.95 3.168 270)
			(layer "F.Fab")
			(effects
				(font
					(size 0.7 0.7)
					(thickness 0.15)
				)
				(justify left bottom)
			)
		)
		(pad "1" smd roundrect
			(at -0.48 0 270)
			(size 0.59 0.64)
			(layers "F.Cu" "F.Mask" "F.Paste")
			(roundrect_rratio 0.25)
			(net 785 "Net-(D3-C)")
			(pintype "passive")
		)
		(pad "2" smd roundrect
			(at 0.48 0 270)
			(size 0.59 0.64)
			(layers "F.Cu" "F.Mask" "F.Paste")
			(roundrect_rratio 0.25)
			(net 271 "Net-(Q3-D)")
			(pintype "passive")
		)
	)
	(footprint "antmicro-footprints:TSSOP-8_3x3mm_P0.65mm"
		(layer "F.Cu")
		(at 239.274499 133.77)
		(property "Reference" "U45"
			(at 0 -2 0)
			(layer "F.SilkS")
			(effects
				(font
					(size 0.7 0.7)
					(thickness 0.15)
				)
				(justify left bottom)
			)
		)
		(property "Value" "PCA9517ADP"
			(at 0 2.8 0)
			(layer "F.Fab")
			(effects
				(font
					(size 0.7 0.7)
					(thickness 0.15)
				)
				(justify left bottom)
			)
		)
		(property "Datasheet" "https://www.nxp.com/docs/en/data-sheet/PCA9517A.pdf"
			(at 0 0 0)
			(layer "F.Fab")
			(hide yes)
			(effects
				(font
					(size 1.27 1.27)
					(thickness 0.15)
				)
			)
		)
		(property "MPN" "PCA9517ADP,118"
			(at 0 0 0)
			(unlocked yes)
			(layer "F.Fab")
			(hide yes)
			(effects
				(font
					(size 1 1)
					(thickness 0.15)
				)
			)
		)
		(property "Manufacturer" "NXP"
			(at 0 0 0)
			(unlocked yes)
			(layer "F.Fab")
			(hide yes)
			(effects
				(font
					(size 1 1)
					(thickness 0.15)
				)
			)
		)
		(property "Author" "Antmicro"
			(at 0 0 0)
			(unlocked yes)
			(layer "F.Fab")
			(hide yes)
			(effects
				(font
					(size 1 1)
					(thickness 0.15)
				)
			)
		)
		(property "License" "Apache-2.0"
			(at 0 0 0)
			(unlocked yes)
			(layer "F.Fab")
			(hide yes)
			(effects
				(font
					(size 1 1)
					(thickness 0.15)
				)
			)
		)
		(sheetname "/I^{2}C + I3C/")
		(sheetfile "i2c.kicad_sch")
		(attr smd)
		(fp_line
			(start -1.55 1.561)
			(end 1.552 1.561)
			(stroke
				(width 0.15)
				(type solid)
			)
			(layer "F.SilkS")
		)
		(fp_line
			(start -1.525 -1.537)
			(end 1.552 -1.539)
			(stroke
				(width 0.15)
				(type solid)
			)
			(layer "F.SilkS")
		)
		(fp_circle
			(center -1.87 -1.4)
			(end -1.82 -1.4)
			(stroke
				(width 0.15)
				(type solid)
			)
			(fill yes)
			(layer "F.SilkS")
		)
		(fp_rect
			(start -3.15 -1.789)
			(end 3.15 1.811)
			(stroke
				(width 0.05)
				(type solid)
			)
			(fill no)
			(layer "F.CrtYd")
		)
		(fp_line
			(start -1.55 -0.937)
			(end -1.55 1.561)
			(stroke
				(width 0.15)
				(type solid)
			)
			(layer "F.Fab")
		)
		(fp_line
			(start -1.55 -0.937)
			(end -0.949 -1.539)
			(stroke
				(width 0.15)
				(type solid)
			)
			(layer "F.Fab")
		)
		(fp_line
			(start -1.55 1.561)
			(end 1.552 1.561)
			(stroke
				(width 0.15)
				(type solid)
			)
			(layer "F.Fab")
		)
		(fp_line
			(start -0.949 -1.539)
			(end 1.552 -1.539)
			(stroke
				(width 0.15)
				(type solid)
			)
			(layer "F.Fab")
		)
		(fp_line
			(start 1.552 -1.539)
			(end 1.552 1.561)
			(stroke
				(width 0.15)
				(type solid)
			)
			(layer "F.Fab")
		)
		(fp_text user "Author: Antmicro"
			(at -1.789 7.78 0)
			(layer "F.Fab")
			(effects
				(font
					(size 0.7 0.7)
					(thickness 0.15)
				)
				(justify left bottom)
			)
		)
		(fp_text user "${REFERENCE}"
			(at -1.789 6.58 0)
			(layer "F.Fab")
			(effects
				(font
					(size 0.7 0.7)
					(thickness 0.15)
				)
				(justify left bottom)
			)
		)
		(fp_text user "License: Apache-2.0"
			(at -1.789 8.98 0)
			(layer "F.Fab")
			(effects
				(font
					(size 0.7 0.7)
					(thickness 0.15)
				)
				(justify left bottom)
			)
		)
		(pad "1" smd roundrect
			(at -2.148 -0.962)
			(size 1.47 0.4)
			(layers "F.Cu" "F.Mask" "F.Paste")
			(roundrect_rratio 0.25)
			(net 201 "VDDSPD")
			(pinfunction "V_{CC(A)}")
			(pintype "power_in")
		)
		(pad "2" smd roundrect
			(at -2.148 -0.313)
			(size 1.47 0.4)
			(layers "F.Cu" "F.Mask" "F.Paste")
			(roundrect_rratio 0.25)
			(net 460 "/DDR5 RDIMM/DDR.SCL")
			(pinfunction "SCLA")
			(pintype "input")
		)
		(pad "3" smd roundrect
			(at -2.148 0.338)
			(size 1.47 0.4)
			(layers "F.Cu" "F.Mask" "F.Paste")
			(roundrect_rratio 0.25)
			(net 459 "/DDR5 RDIMM/DDR.SDA")
			(pinfunction "SDAA")
			(pintype "bidirectional")
		)
		(pad "4" smd roundrect
			(at -2.148 0.987)
			(size 1.47 0.4)
			(layers "F.Cu" "F.Mask" "F.Paste")
			(roundrect_rratio 0.25)
			(net 1 "GND")
			(pinfunction "GND")
			(pintype "power_in")
		)
		(pad "5" smd roundrect
			(at 2.151 0.987)
			(size 1.47 0.4)
			(layers "F.Cu" "F.Mask" "F.Paste")
			(roundrect_rratio 0.25)
			(net 796 "Net-(U45-EN)")
			(pinfunction "EN")
			(pintype "input")
		)
		(pad "6" smd roundrect
			(at 2.151 0.338)
			(size 1.47 0.4)
			(layers "F.Cu" "F.Mask" "F.Paste")
			(roundrect_rratio 0.25)
			(net 472 "/FPGA banks HD/FPGA_DDR.SDA")
			(pinfunction "SDAB")
			(pintype "bidirectional")
		)
		(pad "7" smd roundrect
			(at 2.151 -0.313)
			(size 1.47 0.4)
			(layers "F.Cu" "F.Mask" "F.Paste")
			(roundrect_rratio 0.25)
			(net 465 "/FPGA banks HD/FPGA_DDR.SCL")
			(pinfunction "SCLB")
			(pintype "input")
		)
		(pad "8" smd roundrect
			(at 2.151 -0.962)
			(size 1.47 0.4)
			(layers "F.Cu" "F.Mask" "F.Paste")
			(roundrect_rratio 0.25)
			(net 151 "+3V3")
			(pinfunction "V_{CC(B)}")
			(pintype "power_in")
		)
	)
	(footprint "antmicro-footprints:NetTie-2_SMD_Pad0.127mm"
		(layer "F.Cu")
		(at 257.267 148.15)
		(descr "Net tie, 2 pin, 0.127mm  SMD pads")
		(tags "net tie")
		(property "Reference" "NT7"
			(at -0.128 -1.345 0)
			(layer "F.SilkS")
			(hide yes)
			(effects
				(font
					(size 0.7 0.7)
					(thickness 0.15)
				)
				(justify left bottom)
			)
		)
		(property "Value" "Net-Tie_P0.127mm"
			(at 0 1.199 0)
			(layer "F.Fab")
			(effects
				(font
					(size 0.7 0.7)
					(thickness 0.15)
				)
				(justify left bottom)
			)
		)
		(property "MPN" ""
			(at 0 0 0)
			(unlocked yes)
			(layer "F.Fab")
			(hide yes)
			(effects
				(font
					(size 1 1)
					(thickness 0.15)
				)
			)
		)
		(property "Manufacturer" ""
			(at 0 0 0)
			(unlocked yes)
			(layer "F.Fab")
			(hide yes)
			(effects
				(font
					(size 1 1)
					(thickness 0.15)
				)
			)
		)
		(property "Author" "Antmicro"
			(at 0 0 0)
			(unlocked yes)
			(layer "F.Fab")
			(hide yes)
			(effects
				(font
					(size 1 1)
					(thickness 0.15)
				)
			)
		)
		(property "License" "Apache-2.0"
			(at 0 0 0)
			(unlocked yes)
			(layer "F.Fab")
			(hide yes)
			(effects
				(font
					(size 1 1)
					(thickness 0.15)
				)
			)
		)
		(property ki_fp_filters "Net*Tie*")
		(sheetname "/Supply/DC-DC IO/")
		(sheetfile "dc-dc-io.kicad_sch")
		(attr through_hole exclude_from_pos_files exclude_from_bom)
		(net_tie_pad_groups "1, 2")
		(fp_poly
			(pts
				(xy -0.0635 -0.0635) (xy 0.0625 -0.0635) (xy 0.0625 0.0635) (xy -0.0635 0.0635)
			)
			(stroke
				(width 0)
				(type solid)
			)
			(fill yes)
			(layer "F.Cu")
		)
		(fp_poly
			(pts
				(xy 0.2 -0.16) (xy 0.29 -0.07) (xy 0.29 0.07) (xy 0.2 0.16) (xy -0.2 0.16) (xy -0.29 0.07) (xy -0.29 -0.06)
				(xy -0.19 -0.16)
			)
			(stroke
				(width 0.05)
				(type solid)
			)
			(fill no)
			(layer "F.CrtYd")
		)
		(fp_text user "Author: Antmicro"
			(at -0.128 4.4 0)
			(layer "F.Fab")
			(effects
				(font
					(size 0.7 0.7)
					(thickness 0.15)
				)
				(justify left bottom)
			)
		)
		(fp_text user "License: Apache-2.0"
			(at -0.128 5.6 0)
			(layer "F.Fab")
			(effects
				(font
					(size 0.7 0.7)
					(thickness 0.15)
				)
				(justify left bottom)
			)
		)
		(fp_text user "${REFERENCE}"
			(at -0.128 3.2 0)
			(layer "F.Fab")
			(effects
				(font
					(size 0.7 0.7)
					(thickness 0.15)
				)
				(justify left bottom)
			)
		)
		(pad "1" smd roundrect
			(at -0.127 0 180)
			(size 0.127 0.127)
			(layers "F.Cu")
			(roundrect_rratio 0.5)
			(chamfer_ratio 0)
			(chamfer top_left bottom_left)
			(net 695 "/Supply/DC-DC IO/VDDQ_SEN_+")
			(pinfunction "1")
			(pintype "passive")
		)
		(pad "2" smd roundrect
			(at 0.126 0)
			(size 0.127 0.127)
			(layers "F.Cu")
			(roundrect_rratio 0.5)
			(chamfer_ratio 0)
			(chamfer top_left bottom_left)
			(net 158 "/Supply/DC-DC IO/VDDQ_local")
			(pinfunction "2")
			(pintype "passive")
		)
	)
	(footprint "antmicro-footprints:C_0402_1005Metric"
		(layer "F.Cu")
		(at 114.773499 139.083 90)
		(descr "Capacitor SMD 0402")
		(tags "capacitor SMD 0402")
		(property "Reference" "C113"
			(at -3.942 0.401501 90)
			(layer "F.SilkS")
			(effects
				(font
					(size 0.7 0.7)
					(thickness 0.15)
				)
				(justify left bottom)
			)
		)
		(property "Value" "C_10u_6.3V_0402"
			(at -1.022927 2.155213 90)
			(layer "F.Fab")
			(effects
				(font
					(size 0.7 0.7)
					(thickness 0.15)
				)
				(justify left bottom)
			)
		)
		(property "Datasheet" "https://www.murata.com/products/productdetail?partno=GRM155R60J106ME15%23"
			(at 0 0 90)
			(layer "F.Fab")
			(hide yes)
			(effects
				(font
					(size 1.27 1.27)
					(thickness 0.15)
				)
			)
		)
		(property "MPN" "GRM155R60J106ME15D"
			(at 0 0 90)
			(unlocked yes)
			(layer "F.Fab")
			(hide yes)
			(effects
				(font
					(size 1 1)
					(thickness 0.15)
				)
			)
		)
		(property "Manufacturer" "Murata"
			(at 0 0 90)
			(unlocked yes)
			(layer "F.Fab")
			(hide yes)
			(effects
				(font
					(size 1 1)
					(thickness 0.15)
				)
			)
		)
		(property "License" "Apache-2.0"
			(at 0 0 90)
			(unlocked yes)
			(layer "F.Fab")
			(hide yes)
			(effects
				(font
					(size 1 1)
					(thickness 0.15)
				)
			)
		)
		(property "Author" "Antmicro"
			(at 0 0 90)
			(unlocked yes)
			(layer "F.Fab")
			(hide yes)
			(effects
				(font
					(size 1 1)
					(thickness 0.15)
				)
			)
		)
		(property "Val" "10u"
			(at 0 0 90)
			(unlocked yes)
			(layer "F.Fab")
			(hide yes)
			(effects
				(font
					(size 1 1)
					(thickness 0.15)
				)
			)
		)
		(property "Voltage" "6.3V"
			(at 0 0 90)
			(unlocked yes)
			(layer "F.Fab")
			(hide yes)
			(effects
				(font
					(size 1 1)
					(thickness 0.15)
				)
			)
		)
		(property "Dielectric" "X5R"
			(at 0 0 90)
			(unlocked yes)
			(layer "F.Fab")
			(hide yes)
			(effects
				(font
					(size 1 1)
					(thickness 0.15)
				)
			)
		)
		(sheetname "/Debug FTDI + VNA/")
		(sheetfile "debug-ftdi.kicad_sch")
		(attr smd)
		(fp_rect
			(start -0.925 -0.47)
			(end 0.925 0.47)
			(stroke
				(width 0.05)
				(type default)
			)
			(fill no)
			(layer "F.CrtYd")
		)
		(fp_line
			(start 0.504 -0.25)
			(end 0.504 0.248)
			(stroke
				(width 0.15)
				(type solid)
			)
			(layer "F.Fab")
		)
		(fp_line
			(start -0.494 -0.25)
			(end 0.504 -0.25)
			(stroke
				(width 0.15)
				(type solid)
			)
			(layer "F.Fab")
		)
		(fp_line
			(start 0.504 0.248)
			(end -0.494 0.248)
			(stroke
				(width 0.15)
				(type solid)
			)
			(layer "F.Fab")
		)
		(fp_line
			(start -0.494 0.248)
			(end -0.494 -0.25)
			(stroke
				(width 0.15)
				(type solid)
			)
			(layer "F.Fab")
		)
		(fp_text user "${REFERENCE}"
			(at -0.939 4.599 90)
			(layer "F.Fab")
			(effects
				(font
					(size 0.7 0.7)
					(thickness 0.15)
				)
				(justify left bottom)
			)
		)
		(fp_text user "License: Apache-2.0"
			(at -0.939 5.799 90)
			(layer "F.Fab")
			(effects
				(font
					(size 0.7 0.7)
					(thickness 0.15)
				)
				(justify left bottom)
			)
		)
		(fp_text user "Author: Antmicro"
			(at -0.939 3.399 90)
			(layer "F.Fab")
			(effects
				(font
					(size 0.7 0.7)
					(thickness 0.15)
				)
				(justify left bottom)
			)
		)
		(pad "1" smd roundrect
			(at -0.48 0 90)
			(size 0.59 0.64)
			(layers "F.Cu" "F.Mask" "F.Paste")
			(roundrect_rratio 0.25)
			(net 1 "GND")
			(pintype "passive")
		)
		(pad "2" smd roundrect
			(at 0.48 0 90)
			(size 0.59 0.64)
			(layers "F.Cu" "F.Mask" "F.Paste")
			(roundrect_rratio 0.25)
			(net 6 "/Debug FTDI + VNA/FTDI_3V3")
			(pintype "passive")
		)
	)
	(footprint "antmicro-footprints:R_0402_1005Metric"
		(layer "F.Cu")
		(at 260.5055 158.671 -90)
		(descr "Resistor SMD 0402")
		(tags "resistor SMD 0402")
		(property "Reference" "R168"
			(at 2.029 -0.4945 90)
			(layer "F.SilkS")
			(effects
				(font
					(size 0.7 0.7)
					(thickness 0.15)
				)
				(justify right bottom)
			)
		)
		(property "Value" "R_0R_0402"
			(at -1.011843 1.772047 90)
			(layer "F.Fab")
			(effects
				(font
					(size 0.7 0.7)
					(thickness 0.15)
				)
				(justify right bottom)
			)
		)
		(property "Datasheet" "https://industrial.panasonic.com/cdbs/www-data/pdf/RDA0000/AOA0000C301.pdf"
			(at 0 0 270)
			(layer "F.Fab")
			(hide yes)
			(effects
				(font
					(size 1.27 1.27)
					(thickness 0.15)
				)
			)
		)
		(property "Manufacturer" "Panasonic"
			(at 0 0 270)
			(unlocked yes)
			(layer "F.Fab")
			(hide yes)
			(effects
				(font
					(size 1 1)
					(thickness 0.15)
				)
			)
		)
		(property "MPN" "ERJ2GE0R00X"
			(at 0 0 270)
			(unlocked yes)
			(layer "F.Fab")
			(hide yes)
			(effects
				(font
					(size 1 1)
					(thickness 0.15)
				)
			)
		)
		(property "Val" "0R"
			(at 0 0 270)
			(unlocked yes)
			(layer "F.Fab")
			(hide yes)
			(effects
				(font
					(size 1 1)
					(thickness 0.15)
				)
			)
		)
		(property "License" "Apache-2.0"
			(at 0 0 270)
			(unlocked yes)
			(layer "F.Fab")
			(hide yes)
			(effects
				(font
					(size 1 1)
					(thickness 0.15)
				)
			)
		)
		(property "Author" "Antmicro"
			(at 0 0 270)
			(unlocked yes)
			(layer "F.Fab")
			(hide yes)
			(effects
				(font
					(size 1 1)
					(thickness 0.15)
				)
			)
		)
		(property "Tolerance" "~"
			(at 0 0 270)
			(unlocked yes)
			(layer "F.Fab")
			(hide yes)
			(effects
				(font
					(size 1 1)
					(thickness 0.15)
				)
			)
		)
		(property "Current" "1A"
			(at 0 0 270)
			(unlocked yes)
			(layer "F.Fab")
			(hide yes)
			(effects
				(font
					(size 1 1)
					(thickness 0.15)
				)
			)
		)
		(sheetname "/Supply/DC-DC IO/")
		(sheetfile "dc-dc-io.kicad_sch")
		(attr smd)
		(fp_rect
			(start -0.925 -0.47)
			(end 0.925 0.47)
			(stroke
				(width 0.05)
				(type default)
			)
			(fill no)
			(layer "F.CrtYd")
		)
		(fp_rect
			(start -0.5 -0.25)
			(end 0.5 0.25)
			(stroke
				(width 0.15)
				(type solid)
			)
			(fill no)
			(layer "F.Fab")
		)
		(fp_text user "Author: Antmicro"
			(at -0.95 4.169 270)
			(layer "F.Fab")
			(effects
				(font
					(size 0.7 0.7)
					(thickness 0.15)
				)
				(justify left bottom)
			)
		)
		(fp_text user "License: Apache-2.0"
			(at -0.95 5.169 270)
			(layer "F.Fab")
			(effects
				(font
					(size 0.7 0.7)
					(thickness 0.15)
				)
				(justify left bottom)
			)
		)
		(fp_text user "${REFERENCE}"
			(at -0.95 3.168 270)
			(layer "F.Fab")
			(effects
				(font
					(size 0.7 0.7)
					(thickness 0.15)
				)
				(justify left bottom)
			)
		)
		(pad "1" smd roundrect
			(at -0.48 0 270)
			(size 0.59 0.64)
			(layers "F.Cu" "F.Mask" "F.Paste")
			(roundrect_rratio 0.25)
			(net 719 "/Supply/DC-DC IO/FB8")
			(pintype "passive")
		)
		(pad "2" smd roundrect
			(at 0.48 0 270)
			(size 0.59 0.64)
			(layers "F.Cu" "F.Mask" "F.Paste")
			(roundrect_rratio 0.25)
			(net 159 "/Supply/DC-DC IO/1V2_local")
			(pintype "passive")
		)
	)
)
